# BASEBOARD_FAB2 (Tioga Pass) — schematic netlist excerpt (pin names and nets, part order shuffled) for the footprints in the layout excerpt that follows; sources: Cadence DE-HDL packaged netlist, KiCad conversion of Wiwynn_Tioga_Pass_MB.brd

U25W5  H5AN4G6NAFR-TFC-GP  pkg MEMORY-G2  page 151
  VDDQ(0)  = P1V2_AUX_BMC
  VSSQ(0)  = GND
  DQU0  = BMC_M_DQ8
  DQSU_C  = BMC_M_DQS1_DN
  VSSQ(1)  = GND
  VDDQ(1)  = P1V2_AUX_BMC
  VPP(0)  = P2V5_AUX_BMC
  VSS(0)  = GND
  VDD(0)  = P1V2_AUX_BMC
  DQSU_T  = BMC_M_DQS1_DP
  DQU1  = BMC_M_DQ9
  VDD(1)  = P1V2_AUX_BMC
  VDDQ(2)  = P1V2_AUX_BMC
  DQU4  = BMC_M_DQ12
  DQU2  = BMC_M_DQ10
  DQU3  = BMC_M_DQ11
  DQU5  = BMC_M_DQ13
  VSSQ(2)  = GND
  VDD(2)  = P1V2_AUX_BMC
  VSSQ(3)  = GND
  DQU6  = BMC_M_DQ14
  DQU7  = BMC_M_DQ15
  VSSQ(4)  = GND
  VDDQ(3)  = P1V2_AUX_BMC
  VSS(1)  = GND
  \dmu#/dbiu#\  = BMC_M_DM1
  VSSQ(5)  = GND
  \dml#/dbil#\  = BMC_M_DM0
  VSSQ(6)  = GND
  VSS(2)  = GND
  VSSQ(7)  = GND
  VDDQ(4)  = P1V2_AUX_BMC
  DQSL_C  = BMC_M_DQS0_DN
  DQL1  = BMC_M_DQ1
  VDDQ(5)  = P1V2_AUX_BMC
  ZQ  = BMC_ZQ
  VDDQ(6)  = P1V2_AUX_BMC
  DQL0  = BMC_M_DQ0
  DQSL_T  = BMC_M_DQS0_DP
  VDD(3)  = P1V2_AUX_BMC
  VSS(3)  = GND
  VDDQ(7)  = P1V2_AUX_BMC
  VSSQ(8)  = GND
  DQL4  = BMC_M_DQ4
  DQL2  = BMC_M_DQ2
  DQL3  = BMC_M_DQ3
  DQL5  = BMC_M_DQ5
  VSSQ(9)  = GND
  VDD(4)  = P1V2_AUX_BMC
  VDDQ(8)  = P1V2_AUX_BMC
  DQL6  = BMC_M_DQ6
  DQL7  = BMC_M_DQ7
  VDDQ(9)  = P1V2_AUX_BMC
  VDD(5)  = P1V2_AUX_BMC
  VSS(4)  = GND
  CKE  = BMC_M_CKE
  ODT  = BMC_M_ODT
  CK_T  = BMC_M_CLK_DP
  CK_C  = BMC_M_CLK_DN
  VSS(5)  = GND
  VDD(6)  = P1V2_AUX_BMC
  \we#/a14\  = BMC_M_WE_N
  \act#\  = BMC_M_MACT_N
  \cs#\  = BMC_M_CS_N
  \ras#/a16\  = BMC_M_RAS_N
  VDD(7)  = P1V2_AUX_BMC
  VREFCA  = BMC_M_VREFCA
  BG0  = BMC_M_BG0
  \a10/ap\  = BMC_M_A10
  \a12/bc#\  = BMC_M_A12
  \cas#/a15\  = BMC_M_CAS_N
  VSS(6)  = GND
  VSS(7)  = GND
  BA0  = BMC_M_BA0
  A4  = BMC_M_A4
  A3  = BMC_M_A3
  BA1  = BMC_M_BA1
  TEN  = GND
  \reset#\  = BMC_M_RST_N
  A6  = BMC_M_A6
  A0  = BMC_M_A0
  A1  = BMC_M_A1
  A5  = BMC_M_A5
  \alert#\  = BMC_M_MALERT_N
  VDD(8)  = P1V2_AUX_BMC
  A8  = BMC_M_A8
  A2  = BMC_M_A2
  A9  = BMC_M_A9
  A7  = BMC_M_A7
  VPP(1)  = P2V5_AUX_BMC
  VSS(8)  = GND
  A11  = BMC_M_A11
  PAR  = BMC_M_PAR
  \nc#t7\  = NC
  A13  = BMC_M_A13
  VDD(9)  = P1V2_AUX_BMC

(kicad_pcb
	(version 20260206)
	(generator "pcbnew")
	(generator_version "10.0")
	(general
		(thickness 1.6)
		(legacy_teardrops no)
	)
	(paper "A4")
	(title_block
		(title "Wiwynn_Tioga_Pass_MB.brd")
		(comment 1 "Tioga Pass / footprint 1895 of 4770 (U25W5), pads 93-96 of 96")
	)
	(layers
		(0 "F.Cu" signal "TOP")
		(4 "In1.Cu" signal "L2GND")
		(6 "In2.Cu" signal "L3")
		(8 "In3.Cu" signal "L4GND")
		(10 "In4.Cu" signal "L5")
		(12 "In5.Cu" signal "L6GND")
		(14 "In6.Cu" signal "L7VCC")
		(16 "In7.Cu" signal "L8VCC")
		(18 "In8.Cu" signal "L9GND")
		(20 "In9.Cu" signal "L10")
		(22 "In10.Cu" signal "L11GND")
		(24 "In11.Cu" signal "L12")
		(26 "In12.Cu" signal "L13GND")
		(2 "B.Cu" signal "BOTTOM")
		(9 "F.Adhes" user "F.Adhesive")
		(11 "B.Adhes" user "B.Adhesive")
		(13 "F.Paste" user "Package Geometry/Pastemask Top")
		(15 "B.Paste" user "Package Geometry/Pastemask Bottom")
		(5 "F.SilkS" user "Ref Des/Silkscreen Top")
		(7 "B.SilkS" user "Ref Des/Silkscreen Bottom")
		(1 "F.Mask" user "Board Geometry/Soldermask Top")
		(3 "B.Mask" user "Board Geometry/Soldermask Bottom")
		(17 "Dwgs.User" user "User.Drawings")
		(19 "Cmts.User" user "User.Comments")
		(21 "Eco1.User" user "User.Eco1")
		(23 "Eco2.User" user "User.Eco2")
		(25 "Edge.Cuts" user "Board Geometry/Outline")
		(27 "Margin" user)
		(31 "F.CrtYd" user "Package Geometry/Place Bound Top")
		(29 "B.CrtYd" user "Package Geometry/Place Bound Bottom")
		(35 "F.Fab" user "Ref Des/Assembly Top")
		(33 "B.Fab" user "Ref Des/Assembly Bottom")
	)
	(footprint ""
		(layer "F.Cu")
		(at 439.722006 -31.4325 180)
		(property "Reference" "U25W5"
			(at 0 0 180)
			(layer "F.SilkS")
			(hide yes)
			(effects
				(font
					(size 1.27 1.27)
				)
			)
		)
		(property "Value" "*"
			(at -8.423656 -16.0909 180)
			(unlocked yes)
			(layer "F.Fab")
			(hide yes)
			(effects
				(font
					(size 1.27 1.016)
					(thickness 0.1524)
				)
			)
		)
		(property "Device Type" "H5AN4G6NAFR-TFC-GP_MEMORY-G2-HA"
			(at -8.423656 -17.6149 180)
			(unlocked yes)
			(layer "F.Fab")
			(hide yes)
			(effects
				(font
					(size 1.27 1.016)
					(thickness 0.1524)
				)
			)
		)
		(duplicate_pad_numbers_are_jumpers no)
		(pad "T3" smd circle
			(at -1.599946 5.999988 180)
			(size 0.3556 0.3556)
			(layers "F.Cu" "F.Mask" "F.Paste")
			(net "BMC_M_PAR")
		)
		(pad "T7" smd circle
			(at 1.599946 5.999988 180)
			(size 0.3556 0.3556)
			(layers "F.Cu" "F.Mask" "F.Paste")
			(net "Net_6479")
		)
		(pad "T8" smd circle
			(at 2.400046 5.999988 180)
			(size 0.3556 0.3556)
			(layers "F.Cu" "F.Mask" "F.Paste")
			(net "BMC_M_A13")
		)
		(pad "T9" smd circle
			(at 3.199892 5.999988 180)
			(size 0.3556 0.3556)
			(layers "F.Cu" "F.Mask" "F.Paste")
			(net "P1V2_AUX_BMC")
		)
	)
)
